(kicad_pcb
	(version 20260206)
	(generator "pcbnew")
	(generator_version "10.0")
	(general
		(thickness 1.6)
		(legacy_teardrops no)
	)
	(paper "A4")
	(title_block
		(title "Bryce Canyon_F.DPB_16315-1-OCP.brd")
		(comment 1 "Bryce Canyon / footprints 1792-1795 of 2223")
	)
	(layers
		(0 "F.Cu" signal "TOP")
		(4 "In1.Cu" signal "L2GND")
		(6 "In2.Cu" signal "L3")
		(8 "In3.Cu" signal "L4GND")
		(10 "In4.Cu" signal "L5")
		(12 "In5.Cu" signal "L6VCC")
		(14 "In6.Cu" signal "L7VCC")
		(16 "In7.Cu" signal "L8")
		(18 "In8.Cu" signal "L9GND")
		(20 "In9.Cu" signal "L10")
		(22 "In10.Cu" signal "L11GND")
		(2 "B.Cu" signal "BOTTOM")
		(9 "F.Adhes" user "F.Adhesive")
		(11 "B.Adhes" user "B.Adhesive")
		(13 "F.Paste" user "Package Geometry/Pastemask Top")
		(15 "B.Paste" user "Package Geometry/Pastemask Bottom")
		(5 "F.SilkS" user "Ref Des/Silkscreen Top")
		(7 "B.SilkS" user "Ref Des/Silkscreen Bottom")
		(1 "F.Mask" user "Board Geometry/Soldermask Top")
		(3 "B.Mask" user "Board Geometry/Soldermask Bottom")
		(17 "Dwgs.User" user "User.Drawings")
		(19 "Cmts.User" user "User.Comments")
		(21 "Eco1.User" user "User.Eco1")
		(23 "Eco2.User" user "User.Eco2")
		(25 "Edge.Cuts" user "Board Geometry/Outline")
		(27 "Margin" user)
		(31 "F.CrtYd" user "Package Geometry/Place Bound Top")
		(29 "B.CrtYd" user "Package Geometry/Place Bound Bottom")
		(35 "F.Fab" user "Ref Des/Assembly Top")
		(33 "B.Fab" user "Ref Des/Assembly Bottom")
	)
	(footprint ""
		(layer "F.Cu")
		(at 300.82236 -65.452752 -90)
		(property "Reference" "C6"
			(at 0 0 270)
			(layer "F.SilkS")
			(hide yes)
			(effects
				(font
					(size 1.27 1.27)
				)
			)
		)
		(property "Value" "SCD1U16V2KX-3GP"
			(at 1.1811 -2.7051 270)
			(unlocked yes)
			(layer "F.Fab")
			(hide yes)
			(effects
				(font
					(size 1.016 1.016)
					(thickness 0.1524)
				)
			)
		)
		(property "Device Type" "C402H22"
			(at 1.1811 -4.2291 270)
			(unlocked yes)
			(layer "F.Fab")
			(hide yes)
			(effects
				(font
					(size 1.016 1.016)
					(thickness 0.1524)
				)
			)
		)
		(duplicate_pad_numbers_are_jumpers no)
		(fp_rect
			(start -0.4318 0.9525)
			(end 0.4318 -0.9525)
			(stroke
				(width 0)
				(type default)
			)
			(fill no)
			(layer "F.CrtYd")
		)
		(fp_rect
			(start -0.4318 0.9525)
			(end 0.4318 -0.9525)
			(stroke
				(width 0)
				(type default)
			)
			(fill no)
			(layer "F.Fab")
		)
		(pad "1" smd custom
			(at 0 -0.4445 270)
			(size 0.1524 0.1524)
			(layers "F.Cu" "F.Mask" "F.Paste")
			(net "P3V3_STBY_B")
			(options
				(clearance outline)
				(anchor circle)
			)
			(primitives
				(gr_poly
					(pts
						(arc
							(start 0.3048 -0.2032)
							(mid 0.275042 -0.275042)
							(end 0.2032 -0.3048)
						)
						(arc
							(start -0.2032 -0.3048)
							(mid -0.275042 -0.275042)
							(end -0.3048 -0.2032)
						)
						(arc
							(start -0.3048 0.2032)
							(mid -0.275042 0.275042)
							(end -0.2032 0.3048)
						)
						(arc
							(start 0.2032 0.3048)
							(mid 0.275042 0.275042)
							(end 0.3048 0.2032)
						)
					)
					(width 0)
					(fill yes)
				)
			)
		)
		(pad "2" smd custom
			(at 0 0.4445 270)
			(size 0.1524 0.1524)
			(layers "F.Cu" "F.Mask" "F.Paste")
			(net "GND")
			(options
				(clearance outline)
				(anchor circle)
			)
			(primitives
				(gr_poly
					(pts
						(arc
							(start 0.3048 -0.2032)
							(mid 0.275042 -0.275042)
							(end 0.2032 -0.3048)
						)
						(arc
							(start -0.2032 -0.3048)
							(mid -0.275042 -0.275042)
							(end -0.3048 -0.2032)
						)
						(arc
							(start -0.3048 0.2032)
							(mid -0.275042 0.275042)
							(end -0.2032 0.3048)
						)
						(arc
							(start 0.2032 0.3048)
							(mid 0.275042 0.275042)
							(end 0.3048 0.2032)
						)
					)
					(width 0)
					(fill yes)
				)
			)
		)
	)
	(footprint ""
		(layer "F.Cu")
		(at 473.961968 -290.20262)
		(property "Reference" "C188"
			(at 0 0 0)
			(layer "F.SilkS")
			(hide yes)
			(effects
				(font
					(size 1.27 1.27)
				)
			)
		)
		(property "Value" "SC4D7U25V5KX-1-GP"
			(at -0.0762 -6.1214 0)
			(unlocked yes)
			(layer "F.Fab")
			(hide yes)
			(effects
				(font
					(size 1.016 1.016)
					(thickness 0.1524)
				)
			)
		)
		(property "Device Type" "C805H58"
			(at -0.0762 -8.1534 0)
			(unlocked yes)
			(layer "F.Fab")
			(hide yes)
			(effects
				(font
					(size 1.016 1.016)
					(thickness 0.1524)
				)
			)
		)
		(duplicate_pad_numbers_are_jumpers no)
		(fp_line
			(start 0.635 0)
			(end -0.635 0)
			(stroke
				(width 0.508)
				(type default)
			)
			(layer "F.SilkS")
		)
		(fp_rect
			(start -0.9652 1.778)
			(end 0.9652 -1.778)
			(stroke
				(width 0)
				(type default)
			)
			(fill no)
			(layer "F.CrtYd")
		)
		(fp_poly
			(pts
				(xy -0.9652 -1.778) (xy 0.9652 -1.778) (xy 0.9652 1.778) (xy -0.9652 1.778)
			)
			(stroke
				(width 0)
				(type default)
			)
			(fill no)
			(layer "F.Fab")
		)
		(pad "1" smd rect
			(at 0 -0.9652)
			(size 1.397 1.143)
			(layers "F.Cu" "F.Mask" "F.Paste")
			(net "P12V_HDD11")
		)
		(pad "2" smd rect
			(at 0 0.9652)
			(size 1.397 1.143)
			(layers "F.Cu" "F.Mask" "F.Paste")
			(net "GND")
		)
	)
	(footprint ""
		(layer "F.Cu")
		(at 447.421 -181.991 90)
		(property "Reference" "C331"
			(at 0 0 90)
			(layer "F.SilkS")
			(hide yes)
			(effects
				(font
					(size 1.27 1.27)
				)
			)
		)
		(property "Value" "SCD01U50V2KX-1GP"
			(at 1.1811 -2.7051 90)
			(unlocked yes)
			(layer "F.Fab")
			(hide yes)
			(effects
				(font
					(size 1.016 1.016)
					(thickness 0.1524)
				)
			)
		)
		(property "Device Type" "C402H22"
			(at 1.1811 -4.2291 90)
			(unlocked yes)
			(layer "F.Fab")
			(hide yes)
			(effects
				(font
					(size 1.016 1.016)
					(thickness 0.1524)
				)
			)
		)
		(duplicate_pad_numbers_are_jumpers no)
		(fp_rect
			(start -0.4318 0.9525)
			(end 0.4318 -0.9525)
			(stroke
				(width 0)
				(type default)
			)
			(fill no)
			(layer "F.CrtYd")
		)
		(fp_rect
			(start -0.4318 0.9525)
			(end 0.4318 -0.9525)
			(stroke
				(width 0)
				(type default)
			)
			(fill no)
			(layer "F.Fab")
		)
		(pad "1" smd custom
			(at 0 -0.4445 90)
			(size 0.1524 0.1524)
			(layers "F.Cu" "F.Mask" "F.Paste")
			(net "HDD_PRSNT_22")
			(options
				(clearance outline)
				(anchor circle)
			)
			(primitives
				(gr_poly
					(pts
						(arc
							(start 0.3048 -0.2032)
							(mid 0.275042 -0.275042)
							(end 0.2032 -0.3048)
						)
						(arc
							(start -0.2032 -0.3048)
							(mid -0.275042 -0.275042)
							(end -0.3048 -0.2032)
						)
						(arc
							(start -0.3048 0.2032)
							(mid -0.275042 0.275042)
							(end -0.2032 0.3048)
						)
						(arc
							(start 0.2032 0.3048)
							(mid 0.275042 0.275042)
							(end 0.3048 0.2032)
						)
					)
					(width 0)
					(fill yes)
				)
			)
		)
		(pad "2" smd custom
			(at 0 0.4445 90)
			(size 0.1524 0.1524)
			(layers "F.Cu" "F.Mask" "F.Paste")
			(net "GND")
			(options
				(clearance outline)
				(anchor circle)
			)
			(primitives
				(gr_poly
					(pts
						(arc
							(start 0.3048 -0.2032)
							(mid 0.275042 -0.275042)
							(end 0.2032 -0.3048)
						)
						(arc
							(start -0.2032 -0.3048)
							(mid -0.275042 -0.275042)
							(end -0.3048 -0.2032)
						)
						(arc
							(start -0.3048 0.2032)
							(mid -0.275042 0.275042)
							(end -0.2032 0.3048)
						)
						(arc
							(start 0.2032 0.3048)
							(mid 0.275042 0.275042)
							(end 0.3048 0.2032)
						)
					)
					(width 0)
					(fill yes)
				)
			)
		)
	)
	(footprint ""
		(layer "F.Cu")
		(at 175.909478 -27.240738 90)
		(property "Reference" "R392"
			(at 0 0 90)
			(layer "F.SilkS")
			(hide yes)
			(effects
				(font
					(size 1.27 1.27)
				)
			)
		)
		(property "Value" "10KR2F-2-GP"
			(at 0.064008 -3.993896 90)
			(unlocked yes)
			(layer "F.Fab")
			(hide yes)
			(effects
				(font
					(size 1.016 1.016)
					(thickness 0.1524)
				)
			)
		)
		(property "Device Type" "R402H16"
			(at 0.064008 -5.517896 90)
			(unlocked yes)
			(layer "F.Fab")
			(hide yes)
			(effects
				(font
					(size 1.016 1.016)
					(thickness 0.1524)
				)
			)
		)
		(duplicate_pad_numbers_are_jumpers no)
		(fp_line
			(start 0.508 -0.9398)
			(end -0.508 -0.9398)
			(stroke
				(width 0.1524)
				(type default)
			)
			(layer "F.SilkS")
		)
		(fp_line
			(start -0.508 -0.9398)
			(end -0.508 0.9398)
			(stroke
				(width 0.1524)
				(type default)
			)
			(layer "F.SilkS")
		)
		(fp_rect
			(start -0.508 0.9398)
			(end 0.508 -0.9398)
			(stroke
				(width 0)
				(type default)
			)
			(fill no)
			(layer "F.CrtYd")
		)
		(fp_rect
			(start -0.508 0.9398)
			(end 0.508 -0.9398)
			(stroke
				(width 0)
				(type default)
			)
			(fill no)
			(layer "F.Fab")
		)
		(pad "1" smd custom
			(at 0 -0.4445 90)
			(size 0.1397 0.1397)
			(layers "F.Cu" "F.Mask" "F.Paste")
			(net "SYS_A_RESET_BUFFER_N")
			(options
				(clearance outline)
				(anchor circle)
			)
			(primitives
				(gr_poly
					(pts
						(arc
							(start -0.1778 -0.2794)
							(mid -0.249642 -0.249642)
							(end -0.2794 -0.1778)
						)
						(arc
							(start -0.2794 0.1778)
							(mid -0.249642 0.249642)
							(end -0.1778 0.2794)
						)
						(arc
							(start 0.1778 0.2794)
							(mid 0.249642 0.249642)
							(end 0.2794 0.1778)
						)
						(arc
							(start 0.2794 -0.1778)
							(mid 0.249642 -0.249642)
							(end 0.1778 -0.2794)
						)
					)
					(width 0)
					(fill yes)
				)
			)
		)
		(pad "2" smd custom
			(at 0 0.4445 90)
			(size 0.1397 0.1397)
			(layers "F.Cu" "F.Mask" "F.Paste")
			(net "GND")
			(options
				(clearance outline)
				(anchor circle)
			)
			(primitives
				(gr_poly
					(pts
						(arc
							(start -0.1778 -0.2794)
							(mid -0.249642 -0.249642)
							(end -0.2794 -0.1778)
						)
						(arc
							(start -0.2794 0.1778)
							(mid -0.249642 0.249642)
							(end -0.1778 0.2794)
						)
						(arc
							(start 0.1778 0.2794)
							(mid 0.249642 0.249642)
							(end 0.2794 0.1778)
						)
						(arc
							(start 0.2794 -0.1778)
							(mid 0.249642 -0.249642)
							(end 0.1778 -0.2794)
						)
					)
					(width 0)
					(fill yes)
				)
			)
		)
	)
)
